FILE_TYPE = MULTI_PHYS_TABLE;
PART 'SOCKET_P_MECH_A'
CLASS='MECHANICAL'
{==================================================================================================================================================================================}
: SKT_NUMBER  | PACK_TYPE | MATERIAL  |  PART_NUMBER    = EnvComp             | PART_NUMBER  | DESCRIPTION               | JEDEC_TYPE                  | HEIGHT     | COMPONENT_TYPE | SPEED_URL | Status |RPL| AML | Bus_Unit | Days ;
{==================================================================================================================================================================================}
'P0'         | 'LEFT'    | 'PLASTIC' | 'H37604-201'(!) = 'NO;NO;NO;NO;NO;NO'      | 'H37604-201' | 'SOCKET_P0 LEFT VendorT'   | 'XLGA3647_H3760X_LEFT_P0'  | '0.276 IN' | 'BGA'          | 'http://speed.intel.com:8081/speed/module/pdm/item/pdm_item_detail_direct.asp?item_cde=H37604-201&item_rev=01&url_param=unused' | 'Design' | 'YES' | '2' | 'ATD SUBSTRATE' | '???' 
'P0'         | 'LEFT'    | 'EMPTY'   | 'H37604-201'(!) = 'NO;NO;NO;NO;NO;NO'      | 'H37604-201' | 'SOCKET_P0 LEFT VendorT'   | 'XLGA3647_H3760X_LEFT_P0'  | '0.276 IN' | 'BGA'          | 'http://speed.intel.com:8081/speed/module/pdm/item/pdm_item_detail_direct.asp?item_cde=H37604-201&item_rev=01&url_param=unused' | 'Design' | 'YES' | '2' | 'ATD SUBSTRATE' | '???' 
'P0'         | 'RIGHT'   | 'PLASTIC' | 'H37604-101'(!) = 'NO;NO;NO;NO;NO;NO'      | 'H37604-101' | 'SOCKET_P0 RIGHT VendorT'  | 'XLGA3647_H3760X_RIGHT_P0' | '0.276 IN' | 'BGA'          | 'http://speed.intel.com:8081/speed/module/pdm/item/pdm_item_detail_direct.asp?item_cde=H37604-101&item_rev=01&url_param=unused' | 'Design' | 'YES' | '1' | 'ATD SUBSTRATE' | '???' 
'P0'         | 'RIGHT'   | 'EMPTY'   | 'H37604-101'(!) = 'NO;NO;NO;NO;NO;NO'      | 'H37604-101' | 'SOCKET_P0 RIGHT VendorT'  | 'XLGA3647_H3760X_RIGHT_P0' | '0.276 IN' | 'BGA'          | 'http://speed.intel.com:8081/speed/module/pdm/item/pdm_item_detail_direct.asp?item_cde=H37604-101&item_rev=01&url_param=unused' | 'Design' | 'YES' | '1' | 'ATD SUBSTRATE' | '???' 
END_PART
END.
